(kicad_pcb
	(version 20241229)
	(generator "pcbnew")
	(generator_version "9.0")
	(general
		(thickness 1.62)
		(legacy_teardrops no)
	)
	(paper "A4")
	(title_block
		(title "OCuLink to 10GbE adapter")
		(date "2026-02-23")
		(rev "1.1.0")
		(company "Antmicro Ltd")
		(comment 1 "www.antmicro.com")
		(comment 9 "footprints 220-225 of 510")
	)
	(layers
		(0 "F.Cu" signal)
		(4 "In1.Cu" signal)
		(6 "In2.Cu" signal)
		(8 "In3.Cu" signal)
		(10 "In4.Cu" signal)
		(12 "In5.Cu" signal)
		(14 "In6.Cu" signal)
		(2 "B.Cu" signal)
		(9 "F.Adhes" user "F.Adhesive")
		(11 "B.Adhes" user "B.Adhesive")
		(13 "F.Paste" user)
		(15 "B.Paste" user)
		(5 "F.SilkS" user "F.Silkscreen")
		(7 "B.SilkS" user "B.Silkscreen")
		(1 "F.Mask" user)
		(3 "B.Mask" user)
		(17 "Dwgs.User" user "User.Drawings")
		(19 "Cmts.User" user "User.Comments")
		(21 "Eco1.User" user "User.Eco1")
		(23 "Eco2.User" user "User.Eco2")
		(25 "Edge.Cuts" user)
		(27 "Margin" user)
		(31 "F.CrtYd" user "F.Courtyard")
		(29 "B.CrtYd" user "B.Courtyard")
		(35 "F.Fab" user)
		(33 "B.Fab" user)
	)
	(footprint "antmicro-footprints:R_0402_1005Metric"
		(layer "F.Cu")
		(at 56.1 92.849999 90)
		(descr "Resistor SMD 0402")
		(tags "resistor SMD 0402")
		(property "Reference" "R29"
			(at -1.670001 -1.1 180)
			(layer "F.SilkS")
			(effects
				(font
					(size 0.7 0.7)
					(thickness 0.15)
				)
				(justify left bottom)
			)
		)
		(property "Value" "R_20k_0402"
			(at -1.011843 1.772046 90)
			(layer "F.Fab")
			(hide yes)
			(effects
				(font
					(size 0.7 0.7)
					(thickness 0.15)
				)
				(justify left bottom)
			)
		)
		(property "Datasheet" "https://www.bourns.com/docs/product-datasheets/cr.pdf"
			(at 0 0 90)
			(layer "F.Fab")
			(hide yes)
			(effects
				(font
					(size 1.27 1.27)
					(thickness 0.15)
				)
			)
		)
		(property "Description" "SMD Chip Resistor, 20 kohm, ± 1%, 62.5 mW, 0402 [1005 Metric], Thick Film, General Purpose"
			(at 0 0 90)
			(layer "F.Fab")
			(hide yes)
			(effects
				(font
					(size 1.27 1.27)
					(thickness 0.15)
				)
			)
		)
		(property "MPN" "CR0402-FX-2002GLF"
			(at 0 0 90)
			(unlocked yes)
			(layer "F.Fab")
			(hide yes)
			(effects
				(font
					(size 1 1)
					(thickness 0.15)
				)
			)
		)
		(property "Manufacturer" "Bourns"
			(at 0 0 90)
			(unlocked yes)
			(layer "F.Fab")
			(hide yes)
			(effects
				(font
					(size 1 1)
					(thickness 0.15)
				)
			)
		)
		(property "License" "Apache-2.0"
			(at 0 0 90)
			(unlocked yes)
			(layer "F.Fab")
			(hide yes)
			(effects
				(font
					(size 1 1)
					(thickness 0.15)
				)
			)
		)
		(property "Author" "Antmicro"
			(at 0 0 90)
			(unlocked yes)
			(layer "F.Fab")
			(hide yes)
			(effects
				(font
					(size 1 1)
					(thickness 0.15)
				)
			)
		)
		(property "Val" "20k"
			(at 0 0 90)
			(unlocked yes)
			(layer "F.Fab")
			(hide yes)
			(effects
				(font
					(size 1 1)
					(thickness 0.15)
				)
			)
		)
		(property "Tolerance" "1%"
			(at 0 0 90)
			(unlocked yes)
			(layer "F.Fab")
			(hide yes)
			(effects
				(font
					(size 1 1)
					(thickness 0.15)
				)
			)
		)
		(sheetname "/Power/")
		(sheetfile "power.kicad_sch")
		(attr smd)
		(fp_rect
			(start -0.925 -0.47)
			(end 0.925 0.47)
			(stroke
				(width 0.05)
				(type default)
			)
			(fill no)
			(layer "F.CrtYd")
		)
		(fp_rect
			(start -0.5 -0.25)
			(end 0.5 0.25)
			(stroke
				(width 0.15)
				(type solid)
			)
			(fill no)
			(layer "F.Fab")
		)
		(pad "1" smd roundrect
			(at -0.48 0 90)
			(size 0.59 0.64)
			(layers "F.Cu" "F.Mask" "F.Paste")
			(roundrect_rratio 0.25)
			(net 331 "/Power/DVDD_FB")
			(pintype "passive")
		)
		(pad "2" smd roundrect
			(at 0.48 0 90)
			(size 0.59 0.64)
			(layers "F.Cu" "F.Mask" "F.Paste")
			(roundrect_rratio 0.25)
			(net 311 "/Power/+DVDD_OUT")
			(pintype "passive")
		)
	)
	(footprint "antmicro-footprints:C_0603_1608Metric_EIA"
		(layer "F.Cu")
		(at 51.9 96.199999 -90)
		(descr "Capacitor SMD 0603, IPC-7351 Density Level A")
		(tags "Capacitor 0603")
		(property "Reference" "C41"
			(at 1.190001 0.38 90)
			(layer "F.SilkS")
			(effects
				(font
					(size 0.7 0.7)
					(thickness 0.15)
				)
				(justify right top)
			)
		)
		(property "Value" "C_22u_16V_0603"
			(at -1.42757 1.770288 90)
			(layer "F.Fab")
			(hide yes)
			(effects
				(font
					(size 0.7 0.7)
					(thickness 0.15)
				)
				(justify right top)
			)
		)
		(property "Datasheet" "https://product.samsungsem.com/mlcc/CL10A226MO7JZN.do"
			(at 0 0 90)
			(layer "F.Fab")
			(hide yes)
			(effects
				(font
					(size 1.27 1.27)
					(thickness 0.15)
				)
			)
		)
		(property "Description" "SMD Multilayer Ceramic Capacitor"
			(at 0 0 90)
			(layer "F.Fab")
			(hide yes)
			(effects
				(font
					(size 1.27 1.27)
					(thickness 0.15)
				)
			)
		)
		(property "MPN" "CL10A226MO7JZNC"
			(at 0 0 270)
			(unlocked yes)
			(layer "F.Fab")
			(hide yes)
			(effects
				(font
					(size 1 1)
					(thickness 0.15)
				)
			)
		)
		(property "Manufacturer" "Samsung Electro-Mechanics"
			(at 0 0 270)
			(unlocked yes)
			(layer "F.Fab")
			(hide yes)
			(effects
				(font
					(size 1 1)
					(thickness 0.15)
				)
			)
		)
		(property "License" "Apache-2.0"
			(at 0 0 270)
			(unlocked yes)
			(layer "F.Fab")
			(hide yes)
			(effects
				(font
					(size 1 1)
					(thickness 0.15)
				)
			)
		)
		(property "Author" "Antmicro"
			(at 0 0 270)
			(unlocked yes)
			(layer "F.Fab")
			(hide yes)
			(effects
				(font
					(size 1 1)
					(thickness 0.15)
				)
			)
		)
		(property "Val" "22u"
			(at 0 0 270)
			(unlocked yes)
			(layer "F.Fab")
			(hide yes)
			(effects
				(font
					(size 1 1)
					(thickness 0.15)
				)
			)
		)
		(property "Voltage" "16V"
			(at 0 0 270)
			(unlocked yes)
			(layer "F.Fab")
			(hide yes)
			(effects
				(font
					(size 1 1)
					(thickness 0.15)
				)
			)
		)
		(property "Dielectric" ""
			(at 0 0 270)
			(unlocked yes)
			(layer "F.Fab")
			(hide yes)
			(effects
				(font
					(size 1 1)
					(thickness 0.15)
				)
			)
		)
		(property "Public" "False"
			(at 0 0 270)
			(unlocked yes)
			(layer "F.Fab")
			(hide yes)
			(effects
				(font
					(size 1 1)
					(thickness 0.15)
				)
			)
		)
		(sheetname "/Power/")
		(sheetfile "power.kicad_sch")
		(attr smd)
		(fp_line
			(start -0.15 0.55)
			(end 0.15 0.55)
			(stroke
				(width 0.15)
				(type solid)
			)
			(layer "F.SilkS")
		)
		(fp_line
			(start -0.15 -0.55)
			(end 0.15 -0.55)
			(stroke
				(width 0.15)
				(type solid)
			)
			(layer "F.SilkS")
		)
		(fp_rect
			(start -1.25 -0.65)
			(end 1.25 0.65)
			(stroke
				(width 0.05)
				(type solid)
			)
			(fill no)
			(layer "F.CrtYd")
		)
		(fp_rect
			(start -0.8 -0.45)
			(end 0.8 0.45)
			(stroke
				(width 0.15)
				(type solid)
			)
			(fill no)
			(layer "F.Fab")
		)
		(pad "1" smd roundrect
			(at -0.7 0 270)
			(size 0.8 1.1)
			(layers "F.Cu" "F.Mask" "F.Paste")
			(roundrect_rratio 0.2)
			(net 28 "GND")
			(pintype "passive")
		)
		(pad "2" smd roundrect
			(at 0.7 0 270)
			(size 0.8 1.1)
			(layers "F.Cu" "F.Mask" "F.Paste")
			(roundrect_rratio 0.2)
			(net 314 "VCC")
			(pintype "passive")
		)
	)
	(footprint "antmicro-footprints:C_0402_1005Metric"
		(layer "F.Cu")
		(at 86.43 58.111999 90)
		(descr "Capacitor SMD 0402")
		(tags "capacitor SMD 0402")
		(property "Reference" "C37"
			(at -1.130001 2.41 90)
			(layer "F.SilkS")
			(effects
				(font
					(size 0.7 0.7)
					(thickness 0.15)
				)
				(justify left bottom)
			)
		)
		(property "Value" "C_100n_0402"
			(at -1.022927 2.155213 90)
			(layer "F.Fab")
			(hide yes)
			(effects
				(font
					(size 0.7 0.7)
					(thickness 0.15)
				)
				(justify left bottom)
			)
		)
		(property "Datasheet" "https://www.murata.com/products/productdetail?partno=GRM155R61H104KE14%23"
			(at 0 0 90)
			(layer "F.Fab")
			(hide yes)
			(effects
				(font
					(size 1.27 1.27)
					(thickness 0.15)
				)
			)
		)
		(property "Description" "SMD Multilayer Ceramic Capacitor, 0.1 µF, 50 V, 0402 [1005 Metric], ± 10%, X5R, GRM Series"
			(at 0 0 90)
			(layer "F.Fab")
			(hide yes)
			(effects
				(font
					(size 1.27 1.27)
					(thickness 0.15)
				)
			)
		)
		(property "MPN" "GRM155R61H104KE14D"
			(at 0 0 90)
			(unlocked yes)
			(layer "F.Fab")
			(hide yes)
			(effects
				(font
					(size 1 1)
					(thickness 0.15)
				)
			)
		)
		(property "Val" "100n"
			(at 0 0 90)
			(unlocked yes)
			(layer "F.Fab")
			(hide yes)
			(effects
				(font
					(size 1 1)
					(thickness 0.15)
				)
			)
		)
		(property "Voltage" "50V"
			(at 0 0 90)
			(unlocked yes)
			(layer "F.Fab")
			(hide yes)
			(effects
				(font
					(size 1 1)
					(thickness 0.15)
				)
			)
		)
		(property "Dielectric" "X5R"
			(at 0 0 90)
			(unlocked yes)
			(layer "F.Fab")
			(hide yes)
			(effects
				(font
					(size 1 1)
					(thickness 0.15)
				)
			)
		)
		(property "Manufacturer" "Murata"
			(at 0 0 90)
			(unlocked yes)
			(layer "F.Fab")
			(hide yes)
			(effects
				(font
					(size 1 1)
					(thickness 0.15)
				)
			)
		)
		(property "License" "Apache-2.0"
			(at 0 0 90)
			(unlocked yes)
			(layer "F.Fab")
			(hide yes)
			(effects
				(font
					(size 1 1)
					(thickness 0.15)
				)
			)
		)
		(property "Author" "Antmicro"
			(at 0 0 90)
			(unlocked yes)
			(layer "F.Fab")
			(hide yes)
			(effects
				(font
					(size 1 1)
					(thickness 0.15)
				)
			)
		)
		(sheetname "/Power/")
		(sheetfile "power.kicad_sch")
		(attr smd)
		(fp_rect
			(start -0.925 -0.47)
			(end 0.925 0.47)
			(stroke
				(width 0.05)
				(type default)
			)
			(fill no)
			(layer "F.CrtYd")
		)
		(fp_line
			(start 0.504 -0.25)
			(end 0.504 0.248)
			(stroke
				(width 0.15)
				(type solid)
			)
			(layer "F.Fab")
		)
		(fp_line
			(start -0.494 -0.25)
			(end 0.504 -0.25)
			(stroke
				(width 0.15)
				(type solid)
			)
			(layer "F.Fab")
		)
		(fp_line
			(start 0.504 0.248)
			(end -0.494 0.248)
			(stroke
				(width 0.15)
				(type solid)
			)
			(layer "F.Fab")
		)
		(fp_line
			(start -0.494 0.248)
			(end -0.494 -0.25)
			(stroke
				(width 0.15)
				(type solid)
			)
			(layer "F.Fab")
		)
		(pad "1" smd roundrect
			(at -0.48 0 90)
			(size 0.59 0.64)
			(layers "F.Cu" "F.Mask" "F.Paste")
			(roundrect_rratio 0.25)
			(net 28 "GND")
			(pintype "passive")
		)
		(pad "2" smd roundrect
			(at 0.48 0 90)
			(size 0.59 0.64)
			(layers "F.Cu" "F.Mask" "F.Paste")
			(roundrect_rratio 0.25)
			(net 43 "Net-(C37-Pad2)")
			(pintype "passive")
		)
	)
	(footprint "antmicro-footprints:C_0603_1608Metric_EIA"
		(layer "F.Cu")
		(at 53.25 88.500001 -90)
		(descr "Capacitor SMD 0603, IPC-7351 Density Level A")
		(tags "Capacitor 0603")
		(property "Reference" "C13"
			(at 1.259999 1.37 270)
			(layer "F.SilkS")
			(effects
				(font
					(size 0.7 0.7)
					(thickness 0.15)
				)
				(justify right top)
			)
		)
		(property "Value" "C_22u_16V_0603"
			(at -1.42757 1.770288 90)
			(layer "F.Fab")
			(hide yes)
			(effects
				(font
					(size 0.7 0.7)
					(thickness 0.15)
				)
				(justify right top)
			)
		)
		(property "Datasheet" "https://product.samsungsem.com/mlcc/CL10A226MO7JZN.do"
			(at 0 0 90)
			(layer "F.Fab")
			(hide yes)
			(effects
				(font
					(size 1.27 1.27)
					(thickness 0.15)
				)
			)
		)
		(property "Description" "SMD Multilayer Ceramic Capacitor"
			(at 0 0 90)
			(layer "F.Fab")
			(hide yes)
			(effects
				(font
					(size 1.27 1.27)
					(thickness 0.15)
				)
			)
		)
		(property "MPN" "CL10A226MO7JZNC"
			(at 0 0 270)
			(unlocked yes)
			(layer "F.Fab")
			(hide yes)
			(effects
				(font
					(size 1 1)
					(thickness 0.15)
				)
			)
		)
		(property "Manufacturer" "Samsung Electro-Mechanics"
			(at 0 0 270)
			(unlocked yes)
			(layer "F.Fab")
			(hide yes)
			(effects
				(font
					(size 1 1)
					(thickness 0.15)
				)
			)
		)
		(property "License" "Apache-2.0"
			(at 0 0 270)
			(unlocked yes)
			(layer "F.Fab")
			(hide yes)
			(effects
				(font
					(size 1 1)
					(thickness 0.15)
				)
			)
		)
		(property "Author" "Antmicro"
			(at 0 0 270)
			(unlocked yes)
			(layer "F.Fab")
			(hide yes)
			(effects
				(font
					(size 1 1)
					(thickness 0.15)
				)
			)
		)
		(property "Val" "22u"
			(at 0 0 270)
			(unlocked yes)
			(layer "F.Fab")
			(hide yes)
			(effects
				(font
					(size 1 1)
					(thickness 0.15)
				)
			)
		)
		(property "Voltage" "16V"
			(at 0 0 270)
			(unlocked yes)
			(layer "F.Fab")
			(hide yes)
			(effects
				(font
					(size 1 1)
					(thickness 0.15)
				)
			)
		)
		(property "Dielectric" ""
			(at 0 0 270)
			(unlocked yes)
			(layer "F.Fab")
			(hide yes)
			(effects
				(font
					(size 1 1)
					(thickness 0.15)
				)
			)
		)
		(property "Public" "False"
			(at 0 0 270)
			(unlocked yes)
			(layer "F.Fab")
			(hide yes)
			(effects
				(font
					(size 1 1)
					(thickness 0.15)
				)
			)
		)
		(sheetname "/Power/")
		(sheetfile "power.kicad_sch")
		(attr smd)
		(fp_line
			(start -0.15 0.55)
			(end 0.15 0.55)
			(stroke
				(width 0.15)
				(type solid)
			)
			(layer "F.SilkS")
		)
		(fp_line
			(start -0.15 -0.55)
			(end 0.15 -0.55)
			(stroke
				(width 0.15)
				(type solid)
			)
			(layer "F.SilkS")
		)
		(fp_rect
			(start -1.25 -0.65)
			(end 1.25 0.65)
			(stroke
				(width 0.05)
				(type solid)
			)
			(fill no)
			(layer "F.CrtYd")
		)
		(fp_rect
			(start -0.8 -0.45)
			(end 0.8 0.45)
			(stroke
				(width 0.15)
				(type solid)
			)
			(fill no)
			(layer "F.Fab")
		)
		(pad "1" smd roundrect
			(at -0.7 0 270)
			(size 0.8 1.1)
			(layers "F.Cu" "F.Mask" "F.Paste")
			(roundrect_rratio 0.2)
			(net 28 "GND")
			(pintype "passive")
		)
		(pad "2" smd roundrect
			(at 0.7 0 270)
			(size 0.8 1.1)
			(layers "F.Cu" "F.Mask" "F.Paste")
			(roundrect_rratio 0.2)
			(net 314 "VCC")
			(pintype "passive")
		)
	)
	(footprint "antmicro-footprints:TP_SMD_0.75mm"
		(layer "F.Cu")
		(at 63.41 65.443001)
		(property "Reference" "TP23"
			(at -1.66 -0.813001 0)
			(layer "F.SilkS")
			(effects
				(font
					(size 0.7 0.7)
					(thickness 0.15)
				)
				(justify left bottom)
			)
		)
		(property "Value" "TP_0.75mm_SMD"
			(at 0 1.2 0)
			(layer "F.Fab")
			(hide yes)
			(effects
				(font
					(size 0.7 0.7)
					(thickness 0.15)
				)
				(justify left bottom)
			)
		)
		(property "Description" "SMT test point"
			(at 0 0 0)
			(layer "F.Fab")
			(hide yes)
			(effects
				(font
					(size 1.27 1.27)
					(thickness 0.15)
				)
			)
		)
		(property "MPN" ""
			(at 0 0 0)
			(unlocked yes)
			(layer "F.Fab")
			(hide yes)
			(effects
				(font
					(size 1 1)
					(thickness 0.15)
				)
			)
		)
		(property "Manufacturer" ""
			(at 0 0 0)
			(unlocked yes)
			(layer "F.Fab")
			(hide yes)
			(effects
				(font
					(size 1 1)
					(thickness 0.15)
				)
			)
		)
		(property "Author" "Antmicro"
			(at 0 0 0)
			(unlocked yes)
			(layer "F.Fab")
			(hide yes)
			(effects
				(font
					(size 1 1)
					(thickness 0.15)
				)
			)
		)
		(property "License" "Apache-2.0"
			(at 0 0 0)
			(unlocked yes)
			(layer "F.Fab")
			(hide yes)
			(effects
				(font
					(size 1 1)
					(thickness 0.15)
				)
			)
		)
		(sheetname "/Power/")
		(sheetfile "power.kicad_sch")
		(attr exclude_from_pos_files exclude_from_bom)
		(fp_circle
			(center 0 0)
			(end 0.475 0)
			(stroke
				(width 0.05)
				(type default)
			)
			(fill no)
			(layer "F.CrtYd")
		)
		(pad "1" smd circle
			(at 0 0)
			(size 0.75 0.75)
			(layers "F.Cu" "F.Mask")
			(net 350 "/Power/+12V_IN")
			(pinfunction "1")
			(pintype "passive")
		)
	)
	(footprint "antmicro-footprints:C_0603_1608Metric_EIA"
		(layer "F.Cu")
		(at 60.649997 91.799999)
		(descr "Capacitor SMD 0603, IPC-7351 Density Level A")
		(tags "Capacitor 0603")
		(property "Reference" "C44"
			(at -3.389997 -0.659999 0)
			(layer "F.SilkS")
			(effects
				(font
					(size 0.7 0.7)
					(thickness 0.15)
				)
				(justify left bottom)
			)
		)
		(property "Value" "C_22u_16V_0603"
			(at -1.42757 1.770288 0)
			(layer "F.Fab")
			(hide yes)
			(effects
				(font
					(size 0.7 0.7)
					(thickness 0.15)
				)
				(justify left bottom)
			)
		)
		(property "Datasheet" "https://product.samsungsem.com/mlcc/CL10A226MO7JZN.do"
			(at 0 0 0)
			(layer "F.Fab")
			(hide yes)
			(effects
				(font
					(size 1.27 1.27)
					(thickness 0.15)
				)
			)
		)
		(property "Description" "SMD Multilayer Ceramic Capacitor"
			(at 0 0 0)
			(layer "F.Fab")
			(hide yes)
			(effects
				(font
					(size 1.27 1.27)
					(thickness 0.15)
				)
			)
		)
		(property "MPN" "CL10A226MO7JZNC"
			(at 0 0 0)
			(unlocked yes)
			(layer "F.Fab")
			(hide yes)
			(effects
				(font
					(size 1 1)
					(thickness 0.15)
				)
			)
		)
		(property "Manufacturer" "Samsung Electro-Mechanics"
			(at 0 0 0)
			(unlocked yes)
			(layer "F.Fab")
			(hide yes)
			(effects
				(font
					(size 1 1)
					(thickness 0.15)
				)
			)
		)
		(property "License" "Apache-2.0"
			(at 0 0 0)
			(unlocked yes)
			(layer "F.Fab")
			(hide yes)
			(effects
				(font
					(size 1 1)
					(thickness 0.15)
				)
			)
		)
		(property "Author" "Antmicro"
			(at 0 0 0)
			(unlocked yes)
			(layer "F.Fab")
			(hide yes)
			(effects
				(font
					(size 1 1)
					(thickness 0.15)
				)
			)
		)
		(property "Val" "22u"
			(at 0 0 0)
			(unlocked yes)
			(layer "F.Fab")
			(hide yes)
			(effects
				(font
					(size 1 1)
					(thickness 0.15)
				)
			)
		)
		(property "Voltage" "16V"
			(at 0 0 0)
			(unlocked yes)
			(layer "F.Fab")
			(hide yes)
			(effects
				(font
					(size 1 1)
					(thickness 0.15)
				)
			)
		)
		(property "Dielectric" ""
			(at 0 0 0)
			(unlocked yes)
			(layer "F.Fab")
			(hide yes)
			(effects
				(font
					(size 1 1)
					(thickness 0.15)
				)
			)
		)
		(property "Public" "False"
			(at 0 0 0)
			(unlocked yes)
			(layer "F.Fab")
			(hide yes)
			(effects
				(font
					(size 1 1)
					(thickness 0.15)
				)
			)
		)
		(sheetname "/Power/")
		(sheetfile "power.kicad_sch")
		(attr smd)
		(fp_line
			(start -0.15 -0.55)
			(end 0.15 -0.55)
			(stroke
				(width 0.15)
				(type solid)
			)
			(layer "F.SilkS")
		)
		(fp_line
			(start -0.15 0.55)
			(end 0.15 0.55)
			(stroke
				(width 0.15)
				(type solid)
			)
			(layer "F.SilkS")
		)
		(fp_rect
			(start -1.25 -0.65)
			(end 1.25 0.65)
			(stroke
				(width 0.05)
				(type solid)
			)
			(fill no)
			(layer "F.CrtYd")
		)
		(fp_rect
			(start -0.8 -0.45)
			(end 0.8 0.45)
			(stroke
				(width 0.15)
				(type solid)
			)
			(fill no)
			(layer "F.Fab")
		)
		(pad "1" smd roundrect
			(at -0.7 0)
			(size 0.8 1.1)
			(layers "F.Cu" "F.Mask" "F.Paste")
			(roundrect_rratio 0.2)
			(net 28 "GND")
			(pintype "passive")
		)
		(pad "2" smd roundrect
			(at 0.7 0)
			(size 0.8 1.1)
			(layers "F.Cu" "F.Mask" "F.Paste")
			(roundrect_rratio 0.2)
			(net 311 "/Power/+DVDD_OUT")
			(pintype "passive")
		)
	)
)
